FILE_TYPE = CONNECTIVITY;
{Allegro Design Entry HDL 17.2-2016 S081 (4005846) 1/11/2022}
"PAGE_NUMBER" = 76;
0"NC";
1"GND\g";
2"GND\g";
3"GND\g";
4"GND\g";
5"GND\g";
6"GND\g";
7"ROM_LS_EN";
8"PVDD18_S5_P0\g";
9"PVDD18_S5_P0\g";
10"P3V3_STBY\g";
11"PVDD18_S5_P0\g";
12"P3V3_STBY\g";
13"PVDD18_S5_P0\g";
14"P3V3_STBY\g";
15"SPI_CPU0_D2";
16"SPI_CPU0_D0";
17"SPI_CPU0_D1";
18"SPI_CPU0_D3";
19"ROM_LS_EN";
20"SPI_CPU0_LVC3_R_TPM_CS_N";
21"SPI_CPU0_LVC3_CS1_N";
22"ROM_SD_LS_OE";
23"SPI_CPU0_LVC3_CLK";
24"SPI_CPU0_LVC3_CS0_N";
25"SPI_CPU0_CLK";
26"SPI_CPU0_CS0_N";
27"SPI_CPU0_CS1_N";
28"SPI_CPU0_TPM_CS_N";
29"SPI_CPU0_LVC3_SCM_CLK";
30"SPI_CPU0_LVC3_SCM_CS0_N";
31"SPI_CPU0_LVC3_SCM_CS1_N";
32"SPI_CPU0_LVC3_TPM_CS_N";
33"SPI_CPU0_LVC3_D1";
34"SPI_CPU0_LVC3_D0";
35"SPI_CPU0_LVC3_SCM_D0";
36"SPI_CPU0_LVC3_SCM_D1";
37"SPI_CPU0_LVC3_D2";
38"SPI_CPU0_LVC3_SCM_D2";
39"SPI_CPU0_LVC3_D3";
40"SPI_CPU0_LVC3_SCM_D3";
41"SPI_CPU0_D3";
42"SPI_CPU0_D2";
43"SPI_CPU0_D1";
44"SPI_CPU0_D0";
45"SPI_CPU0_TPM_CS_N";
46"SPI_CPU0_CS1_N";
47"SPI_CPU0_CS0_N";
48"SPI_CPU0_LVC3_SCM_CLK";
49"SPI_CPU0_LVC3_SCM_CS0_N";
50"SPI_CPU0_LVC3_SCM_D0";
51"SPI_CPU0_LVC3_SCM_D1";
52"SPI_CPU0_LVC3_SCM_D2";
53"SPI_CPU0_LVC3_TPM_CS_N";
54"SPI_CPU0_LVC3_SCM_D3";
55"SPI_CPU0_LVC3_SCM_CS1_N";
%"UNIVERSAL_POWER"
"1","(-8025,6075)","0","pure_quanta_power","I105";
;
HDL_POWER"PVDD18_S5_P0"
CDS_LIB"pure_quanta_power";
"A"8;
%"Q_RES"
"2","(-8025,5875)","0","pure_quanta","I106";
;
LOCATION"R811"
$SEC"1"
CDS_SEC"1"
MATERIAL"CHIP"
WATTAGE"1/16W"
VALUE"1K"
TOLERANCE"5%"
CDS_LIB"pure_quanta"
PART_NUMBER"TMP_QCS21002JB34"
PACK_TYPE"0402LF";
"A"
$PN"1"8;
"B"
$PN"2"47;
%"Q_RES"
"2","(-8200,5875)","0","pure_quanta","I107";
;
LOCATION"R659"
$SEC"1"
CDS_SEC"1"
TOLERANCE"5%"
WATTAGE"1/16W"
MATERIAL"CHIP"
VALUE"1K"
CDS_LIB"pure_quanta"
PART_NUMBER"TMP_QCS21002JB34"
PACK_TYPE"0402LF";
"A"
$PN"1"8;
"B"
$PN"2"45;
%"Q_RES"
"2","(-8375,5875)","0","pure_quanta","I108";
;
LOCATION"R601"
$SEC"1"
CDS_SEC"1"
MATERIAL"CHIP"
WATTAGE"1/16W"
TOLERANCE"5%"
VALUE"1K"
CDS_LIB"pure_quanta"
PART_NUMBER"TMP_QCS21002JB34"
PACK_TYPE"0402LF";
"A"
$PN"1"8;
"B"
$PN"2"46;
%"Q_RES"
"2","(-2225,5625)","2","pure_quanta","I115";
;
LOCATION"R20"
$SEC"1"
CDS_SEC"1"
VALUE"10K"
TOLERANCE"1%"
MATERIAL"CHIP"
PART_NUMBER"CS31002FB08"
PACK_TYPE"0402LF"
WATTAGE"1/16W"
CDS_LIB"pure_quanta";
"A"
$PN"1"14;
"B"
$PN"2"48;
%"Q_RES"
"2","(-1875,5625)","2","pure_quanta","I116";
;
LOCATION"R21"
$SEC"1"
CDS_SEC"1"
TOLERANCE"5%"
VALUE"1K"
MATERIAL"EMPTY"
PACK_TYPE"0402LF"
PART_NUMBER"TMP_QCS21002JB34"
WATTAGE"1/16W"
CDS_LIB"pure_quanta";
"A"
$PN"1"14;
"B"
$PN"2"50;
%"Q_RES"
"2","(-1700,5625)","2","pure_quanta","I117";
;
LOCATION"R127"
$SEC"1"
CDS_SEC"1"
VALUE"1K"
TOLERANCE"5%"
MATERIAL"EMPTY"
PACK_TYPE"0402LF"
PART_NUMBER"TMP_QCS21002JB34"
WATTAGE"1/16W"
CDS_LIB"pure_quanta";
"A"
$PN"1"14;
"B"
$PN"2"51;
%"Q_RES"
"2","(-1525,5625)","2","pure_quanta","I118";
;
LOCATION"R128"
$SEC"1"
CDS_SEC"1"
VALUE"1K"
TOLERANCE"5%"
MATERIAL"EMPTY"
PACK_TYPE"0402LF"
PART_NUMBER"TMP_QCS21002JB34"
WATTAGE"1/16W"
CDS_LIB"pure_quanta";
"A"
$PN"1"14;
"B"
$PN"2"52;
%"Q_RES"
"2","(-1350,5625)","2","pure_quanta","I119";
;
LOCATION"R129"
$SEC"1"
CDS_SEC"1"
VALUE"1K"
TOLERANCE"5%"
MATERIAL"EMPTY"
WATTAGE"1/16W"
PART_NUMBER"TMP_QCS21002JB34"
PACK_TYPE"0402LF"
CDS_LIB"pure_quanta";
"A"
$PN"1"14;
"B"
$PN"2"54;
%"Q_RES"
"2","(-8550,5875)","0","pure_quanta","I131";
;
LOCATION"R1532"
$SEC"1"
CDS_SEC"1"
TOLERANCE"5%"
WATTAGE"1/16W"
VALUE"1K"
MATERIAL"EMPTY"
CDS_LIB"pure_quanta"
PART_NUMBER"TMP_QCS21002JB34"
PACK_TYPE"0402LF";
"A"
$PN"1"8;
"B"
$PN"2"44;
%"Q_RES"
"2","(-8725,5875)","0","pure_quanta","I132";
;
LOCATION"R1531"
$SEC"1"
CDS_SEC"1"
WATTAGE"1/16W"
TOLERANCE"5%"
MATERIAL"EMPTY"
VALUE"1K"
CDS_LIB"pure_quanta"
PART_NUMBER"TMP_QCS21002JB34"
PACK_TYPE"0402LF";
"A"
$PN"1"8;
"B"
$PN"2"43;
%"Q_RES"
"2","(-8900,5875)","0","pure_quanta","I133";
;
LOCATION"R1530"
$SEC"1"
CDS_SEC"1"
VALUE"1K"
TOLERANCE"5%"
WATTAGE"1/16W"
MATERIAL"EMPTY"
CDS_LIB"pure_quanta"
PART_NUMBER"TMP_QCS21002JB34"
PACK_TYPE"0402LF";
"A"
$PN"1"8;
"B"
$PN"2"42;
%"Q_RES"
"2","(-9075,5875)","0","pure_quanta","I134";
;
LOCATION"R1529"
$SEC"1"
CDS_SEC"1"
WATTAGE"1/16W"
MATERIAL"EMPTY"
VALUE"1K"
TOLERANCE"5%"
CDS_LIB"pure_quanta"
PART_NUMBER"TMP_QCS21002JB34"
PACK_TYPE"0402LF";
"A"
$PN"1"8;
"B"
$PN"2"41;
%"UNIVERSAL_GND"
"1","(-6200,2500)","0","pure_quanta_power","I138";
;
CDS_LIB"pure_quanta_power"
HDL_POWER"GND";
"A"1;
%"UNIVERSAL_GND"
"1","(-4725,2450)","2","pure_quanta_power","I139";
;
CDS_LIB"pure_quanta_power"
HDL_POWER"GND";
"A"2;
%"Q_RES"
"2","(-1175,5625)","0","pure_quanta","I148";
;
$LOCATION"R1547"
CDS_LOCATION"R1547"
$SEC"1"
CDS_SEC"1"
VALUE"4.7K"
TOLERANCE"5%"
MATERIAL"CHIP"
CDS_LIB"pure_quanta"
WATTAGE"1/16W"
PART_NUMBER"TMP_QCS24702JB38"
PACK_TYPE"0402LF";
"A"
$PN"1"14;
"B"
$PN"2"53;
%"Q_RES"
"2","(-9250,5875)","0","pure_quanta","I150";
;
$LOCATION"R1567"
CDS_LOCATION"R1567"
$SEC"1"
CDS_SEC"1"
VALUE"4.7K"
TOLERANCE"5%"
WATTAGE"1/16W"
MATERIAL"CHIP"
PART_NUMBER"TMP_QCS24702JB38"
PACK_TYPE"0402LF"
CDS_LIB"pure_quanta";
"A"
$PN"1"8;
"B"
$PN"2"19;
%"Q_RES"
"1","(-3950,4175)","0","pure_quanta","I178";
;
LOCATION"R608"
$SEC"1"
CDS_SEC"1"
VALUE"0"
PACK_TYPE"0402LF"
PART_NUMBER"CS00002JB38"
TOLERANCE"5%"
MATERIAL"CHIP"
WATTAGE"1/16W"
CDS_LIB"pure_quanta";
"B"
$PN"2"32;
"A"
$PN"1"20;
%"Q_RES"
"1","(-3950,4225)","0","pure_quanta","I180";
;
LOCATION"R600"
$SEC"1"
CDS_SEC"1"
VALUE"0"
PACK_TYPE"0402LF"
PART_NUMBER"CS00002JB38"
TOLERANCE"5%"
MATERIAL"CHIP"
WATTAGE"1/16W"
CDS_LIB"pure_quanta";
"B"
$PN"2"31;
"A"
$PN"1"21;
%"Q_RES"
"2","(-1025,5625)","2","pure_quanta","I191";
;
$LOCATION"R1655"
CDS_LOCATION"R1655"
$SEC"1"
CDS_SEC"1"
VALUE"1K"
TOLERANCE"5%"
MATERIAL"EMPTY"
PACK_TYPE"0402LF"
PART_NUMBER"TMP_QCS21002JB34"
WATTAGE"1/16W"
CDS_LIB"pure_quanta";
"A"
$PN"1"14;
"B"
$PN"2"55;
%"UNIVERSAL_POWER"
"1","(-6225,4100)","0","pure_quanta_power","I192";
;
HDL_POWER"PVDD18_S5_P0"
CDS_LIB"pure_quanta_power";
"A"9;
%"Q_RES"
"1","(-4075,2325)","0","pure_quanta","I205";
;
LOCATION"R606"
$SEC"1"
CDS_SEC"1"
VALUE"0"
PACK_TYPE"0402LF"
PART_NUMBER"CS00002JB38"
TOLERANCE"5%"
MATERIAL"CHIP"
WATTAGE"1/16W"
CDS_LIB"pure_quanta";
"B"
$PN"2"38;
"A"
$PN"1"37;
%"Q_RES"
"1","(-4075,2375)","0","pure_quanta","I207";
;
LOCATION"R607"
$SEC"1"
CDS_SEC"1"
VALUE"0"
WATTAGE"1/16W"
MATERIAL"CHIP"
TOLERANCE"5%"
PART_NUMBER"CS00002JB38"
PACK_TYPE"0402LF"
CDS_LIB"pure_quanta";
"B"
$PN"2"40;
"A"
$PN"1"39;
%"Q_RES"
"1","(-4075,2225)","0","pure_quanta","I219";
;
LOCATION"R605"
$SEC"1"
CDS_SEC"1"
VALUE"0"
CDS_LIB"pure_quanta"
WATTAGE"1/16W"
MATERIAL"CHIP"
TOLERANCE"5%"
PART_NUMBER"CS00002JB38"
PACK_TYPE"0402LF";
"B"
$PN"2"36;
"A"
$PN"1"33;
%"Q_RES"
"1","(-4075,2275)","0","pure_quanta","I221";
;
LOCATION"R604"
$SEC"1"
CDS_SEC"1"
VALUE"0"
CDS_LIB"pure_quanta"
WATTAGE"1/16W"
MATERIAL"CHIP"
TOLERANCE"5%"
PART_NUMBER"CS00002JB38"
PACK_TYPE"0402LF";
"B"
$PN"2"35;
"A"
$PN"1"34;
%"Q_RES"
"1","(-3950,4325)","0","pure_quanta","I228";
;
LOCATION"R603"
$SEC"1"
CDS_SEC"1"
VALUE"0"
CDS_LIB"pure_quanta"
WATTAGE"1/16W"
MATERIAL"CHIP"
TOLERANCE"5%"
PART_NUMBER"CS00002JB38"
PACK_TYPE"0402LF";
"B"
$PN"2"30;
"A"
$PN"1"24;
%"Q_RES"
"1","(-3950,4275)","0","pure_quanta","I230";
;
LOCATION"R602"
$SEC"1"
CDS_SEC"1"
VALUE"0"
CDS_LIB"pure_quanta"
WATTAGE"1/16W"
MATERIAL"CHIP"
TOLERANCE"5%"
PART_NUMBER"CS00002JB38"
PACK_TYPE"0402LF";
"B"
$PN"2"29;
"A"
$PN"1"23;
%"UNIVERSAL_POWER"
"1","(-4875,5000)","0","pure_quanta_power","I49";
;
HDL_POWER"P3V3_STBY"
CDS_LIB"pure_quanta_power";
"A"10;
%"Q_CAP"
"1","(-4750,4750)","0","pure_quanta","I50";
;
LOCATION"C1104"
$SEC"1"
CDS_SEC"1"
TOLERANCE"10%"
VOLTAGE"25V"
MATERIAL"X7R"
PART_NUMBER"CH4104K1B00"
PACK_TYPE"0402"
VALUE"0.1UF"
CDS_LIB"pure_quanta";
"B"
$PN"2"3;
"A"
$PN"1"10;
%"UNIVERSAL_GND"
"1","(-4750,4550)","2","pure_quanta_power","I51";
;
HDL_POWER"GND"
CDS_LIB"pure_quanta_power";
"A"3;
%"UNIVERSAL_POWER"
"1","(-5975,4975)","0","pure_quanta_power","I52";
;
HDL_POWER"PVDD18_S5_P0"
CDS_LIB"pure_quanta_power";
"A"11;
%"Q_CAP"
"1","(-6100,4750)","2","pure_quanta","I53";
;
LOCATION"C1102"
$SEC"1"
CDS_SEC"1"
PACK_TYPE"0402"
MATERIAL"X7R"
VALUE"0.1UF"
VOLTAGE"25V"
TOLERANCE"10%"
PART_NUMBER"CH4104K1B00"
CDS_LIB"pure_quanta";
"B"
$PN"2"4;
"A"
$PN"1"11;
%"UNIVERSAL_GND"
"1","(-6100,4550)","0","pure_quanta_power","I54";
;
HDL_POWER"GND"
CDS_LIB"pure_quanta_power";
"A"4;
%"UNIVERSAL_GND"
"1","(-4775,3550)","2","pure_quanta_power","I56";
;
CDS_LIB"pure_quanta_power"
HDL_POWER"GND";
"A"5;
%"UNIVERSAL_POWER"
"1","(-4850,2900)","0","pure_quanta_power","I57";
;
HDL_POWER"P3V3_STBY"
CDS_LIB"pure_quanta_power";
"A"12;
%"Q_CAP"
"1","(-4725,2650)","0","pure_quanta","I59";
;
LOCATION"C1105"
$SEC"1"
CDS_SEC"1"
PACK_TYPE"0402"
TOLERANCE"10%"
VOLTAGE"25V"
MATERIAL"X7R"
VALUE"0.1UF"
PART_NUMBER"CH4104K1B00"
CDS_LIB"pure_quanta";
"B"
$PN"2"2;
"A"
$PN"1"12;
%"UNIVERSAL_GND"
"1","(-4825,1700)","2","pure_quanta_power","I62";
;
HDL_POWER"GND"
CDS_LIB"pure_quanta_power";
"A"6;
%"SN74AVC4T774PWR"
"1","(-5425,4175)","0","pure_quanta","I63";
;
LOCATION"U53"
$SEC"1"
CDS_SEC"1"
VALUE"SN74AVC4T774PWR"
PART_TYPE"SMLF"
MATERIAL"IC"
PART_NUMBER"AL04T774K00"
CDS_LIB"pure_quanta"
NEEDS_NO_SIZE"TRUE"
CDS_LMAN_SYM_OUTLINE"-250,450,250,-450";
"VCCA"
$PN"16"11;
"VCCB"
$PN"15"10;
"B1"
$PN"14"24;
"B2"
$PN"13"23;
"B3"
$PN"12"21;
"B4"
$PN"11"20;
"GND"
$PN"10"5;
"OE \B"
$PN"9"22;
"DIR4"
$PN"8"9;
"DIR3"
$PN"7"9;
"A4"
$PN"6"28;
"A3"
$PN"5"27;
"A2"
$PN"4"25;
"A1"
$PN"3"26;
"DIR2"
$PN"2"9;
"DIR1"
$PN"1"9;
%"UNIVERSAL_POWER"
"1","(-6075,2900)","0","pure_quanta_power","I64";
;
HDL_POWER"PVDD18_S5_P0"
CDS_LIB"pure_quanta_power";
"A"13;
%"Q_CAP"
"1","(-6200,2675)","2","pure_quanta","I65";
;
LOCATION"C1103"
$SEC"1"
CDS_SEC"1"
PART_NUMBER"CH4104K1B00"
VALUE"0.1UF"
VOLTAGE"25V"
TOLERANCE"10%"
MATERIAL"X7R"
PACK_TYPE"0402"
CDS_LIB"pure_quanta";
"B"
$PN"2"1;
"A"
$PN"1"13;
%"PI4ULS3V304AZMAEX"
"1","(-5550,2275)","0","pure_quanta","I67";
;
LOCATION"U54"
$SEC"1"
CDS_SEC"1"
VALUE"PI4ULS3V304AZMAEX"
PART_TYPE"SMLF"
MATERIAL"IC"
PART_NUMBER"AL000304005"
CDS_LIB"pure_quanta"
NEEDS_NO_SIZE"TRUE"
CDS_LMAN_SYM_OUTLINE"-250,250,250,-250";
"GND"
$PN"6"6;
"B4"
$PN"7"33;
"B3"
$PN"8"34;
"B2"
$PN"9"37;
"B1"
$PN"10"39;
"VCCA"
$PN"1"13;
"A4"
$PN"5"17;
"EN"
$PN"12"7;
"VCCB"
$PN"11"12;
"A3"
$PN"4"16;
"A2"
$PN"3"15;
"A1"
$PN"2"18;
%"UNIVERSAL_POWER"
"1","(-2225,5925)","2","pure_quanta_power","I96";
;
HDL_POWER"P3V3_STBY"
CDS_LIB"pure_quanta_power";
"A"14;
%"Q_RES"
"2","(-2050,5625)","2","pure_quanta","I97";
;
LOCATION"R610"
$SEC"1"
CDS_SEC"1"
TOLERANCE"5%"
VALUE"1K"
MATERIAL"EMPTY"
CDS_LIB"pure_quanta"
WATTAGE"1/16W"
PART_NUMBER"TMP_QCS21002JB34"
PACK_TYPE"0402LF";
"A"
$PN"1"14;
"B"
$PN"2"49;
END.
